# T6G (Grand Teton) — schematic netlist excerpt (pin names and nets, part order shuffled) for the footprints in the layout excerpt that follows; sources: Cadence DE-HDL packaged netlist, KiCad conversion of 04192023_DAF0TMB3IC0_F0TG_MB_C_brd_V02_OCP.brd

C9922  Q_CAP  22UF 6.3V 20% X6S  pkg C0603  page 144 : A = P3V3_M2_0 ; B = GND
C95  Q_CAP  0.1UF 25V 10% X7R  pkg 0402  page 233 : A = VFG3P3_CLK_GEN ; B = GND

(kicad_pcb
	(version 20260206)
	(generator "pcbnew")
	(generator_version "10.0")
	(general
		(thickness 1.6)
		(legacy_teardrops no)
	)
	(paper "A4")
	(title_block
		(title "04192023_DAF0TMB3IC0_F0TG_MB_C_brd_V02_OCP.brd")
		(comment 1 "Grand Teton / footprints 7340-7341 of 8354")
	)
	(layers
		(0 "F.Cu" signal "TOP")
		(4 "In1.Cu" signal "GND")
		(6 "In2.Cu" signal "IN1")
		(8 "In3.Cu" signal "GND1")
		(10 "In4.Cu" signal "IN2")
		(12 "In5.Cu" signal "GND2")
		(14 "In6.Cu" signal "IN3")
		(16 "In7.Cu" signal "GND3")
		(18 "In8.Cu" signal "VCC")
		(20 "In9.Cu" signal "VCC1")
		(22 "In10.Cu" signal "GND4")
		(24 "In11.Cu" signal "IN4")
		(26 "In12.Cu" signal "GND5")
		(28 "In13.Cu" signal "IN5")
		(30 "In14.Cu" signal "GND6")
		(32 "In15.Cu" signal "IN6")
		(34 "In16.Cu" signal "GND7")
		(2 "B.Cu" signal "BOTTOM")
		(9 "F.Adhes" user "F.Adhesive")
		(11 "B.Adhes" user "B.Adhesive")
		(13 "F.Paste" user "Package Geometry/Pastemask Top")
		(15 "B.Paste" user "Package Geometry/Pastemask Bottom")
		(5 "F.SilkS" user "Ref Des/Silkscreen Top")
		(7 "B.SilkS" user "Ref Des/Silkscreen Bottom")
		(1 "F.Mask" user "Board Geometry/Soldermask Top")
		(3 "B.Mask" user "Board Geometry/Soldermask Bottom")
		(17 "Dwgs.User" user "User.Drawings")
		(19 "Cmts.User" user "User.Comments")
		(21 "Eco1.User" user "User.Eco1")
		(23 "Eco2.User" user "User.Eco2")
		(25 "Edge.Cuts" user "Board Geometry/Outline")
		(27 "Margin" user)
		(31 "F.CrtYd" user "Package Geometry/Place Bound Top")
		(29 "B.CrtYd" user "Package Geometry/Place Bound Bottom")
		(35 "F.Fab" user "Ref Des/Assembly Top")
		(33 "B.Fab" user "Ref Des/Assembly Bottom")
	)
	(footprint ""
		(layer "B.Cu")
		(at 170.12158 -50.107088 180)
		(property "Reference" "C9922"
			(at 0 0 0)
			(layer "B.SilkS")
			(hide yes)
			(effects
				(font
					(size 1.27 1.27)
				)
				(justify mirror)
			)
		)
		(property "Value" ""
			(at 0 0 0)
			(layer "B.Fab")
			(effects
				(font
					(size 1.27 1.27)
				)
				(justify mirror)
			)
		)
		(duplicate_pad_numbers_are_jumpers no)
		(fp_line
			(start 1.2954 0.5842)
			(end 1.2954 -0.5842)
			(stroke
				(width 0.1524)
				(type default)
			)
			(layer "B.SilkS")
		)
		(fp_line
			(start 1.2954 -0.5842)
			(end -1.2954 -0.5842)
			(stroke
				(width 0.1524)
				(type default)
			)
			(layer "B.SilkS")
		)
		(fp_line
			(start -1.2954 0.5842)
			(end 1.2954 0.5842)
			(stroke
				(width 0.1524)
				(type default)
			)
			(layer "B.SilkS")
		)
		(fp_line
			(start -1.2954 -0.5842)
			(end -1.2954 0.5842)
			(stroke
				(width 0.1524)
				(type default)
			)
			(layer "B.SilkS")
		)
		(fp_line
			(start 1.1938 0.4064)
			(end 1.1938 -0.4064)
			(stroke
				(width 0.1)
				(type default)
			)
			(layer "B.Fab")
		)
		(fp_line
			(start 1.1938 -0.4064)
			(end 0.8636 -0.4064)
			(stroke
				(width 0.1)
				(type default)
			)
			(layer "B.Fab")
		)
		(fp_line
			(start 0.8636 0.4572)
			(end 0.8636 0.4064)
			(stroke
				(width 0.1)
				(type default)
			)
			(layer "B.Fab")
		)
		(fp_line
			(start 0.8636 0.4064)
			(end 1.1938 0.4064)
			(stroke
				(width 0.1)
				(type default)
			)
			(layer "B.Fab")
		)
		(fp_line
			(start 0.8636 -0.4064)
			(end 0.8636 -0.4572)
			(stroke
				(width 0.1)
				(type default)
			)
			(layer "B.Fab")
		)
		(fp_line
			(start 0.8636 -0.4572)
			(end -0.8636 -0.4572)
			(stroke
				(width 0.1)
				(type default)
			)
			(layer "B.Fab")
		)
		(fp_line
			(start -0.8636 0.4572)
			(end 0.8636 0.4572)
			(stroke
				(width 0.1)
				(type default)
			)
			(layer "B.Fab")
		)
		(fp_line
			(start -0.8636 0.4064)
			(end -0.8636 0.4572)
			(stroke
				(width 0.1)
				(type default)
			)
			(layer "B.Fab")
		)
		(fp_line
			(start -0.8636 -0.4064)
			(end -1.1938 -0.4064)
			(stroke
				(width 0.1)
				(type default)
			)
			(layer "B.Fab")
		)
		(fp_line
			(start -0.8636 -0.4572)
			(end -0.8636 -0.4064)
			(stroke
				(width 0.1)
				(type default)
			)
			(layer "B.Fab")
		)
		(fp_line
			(start -1.1938 0.4064)
			(end -0.8636 0.4064)
			(stroke
				(width 0.1)
				(type default)
			)
			(layer "B.Fab")
		)
		(fp_line
			(start -1.1938 -0.4064)
			(end -1.1938 0.4064)
			(stroke
				(width 0.1)
				(type default)
			)
			(layer "B.Fab")
		)
		(pad "1" smd rect
			(at 0.7366 0 90)
			(size 0.7112 0.8128)
			(layers "B.Cu" "B.Mask" "B.Paste")
			(net "P3V3_M2_0")
		)
		(pad "2" smd rect
			(at -0.7366 0 90)
			(size 0.7112 0.8128)
			(layers "B.Cu" "B.Mask" "B.Paste")
			(net "GND")
		)
	)
	(footprint ""
		(layer "B.Cu")
		(at 13.650468 -135.44931 90)
		(property "Reference" "C95"
			(at 0 0 90)
			(layer "B.SilkS")
			(hide yes)
			(effects
				(font
					(size 1.27 1.27)
				)
				(justify mirror)
			)
		)
		(property "Value" ""
			(at 0 0 90)
			(layer "B.Fab")
			(effects
				(font
					(size 1.27 1.27)
				)
				(justify mirror)
			)
		)
		(duplicate_pad_numbers_are_jumpers no)
		(fp_line
			(start 0.7874 -0.4064)
			(end -0.7874 -0.4064)
			(stroke
				(width 0.1524)
				(type default)
			)
			(layer "B.SilkS")
		)
		(fp_line
			(start -0.7874 -0.4064)
			(end -0.7874 0.4064)
			(stroke
				(width 0.1524)
				(type default)
			)
			(layer "B.SilkS")
		)
		(fp_line
			(start 0.7874 0.4064)
			(end 0.7874 -0.4064)
			(stroke
				(width 0.1524)
				(type default)
			)
			(layer "B.SilkS")
		)
		(fp_line
			(start -0.7874 0.4064)
			(end 0.7874 0.4064)
			(stroke
				(width 0.1524)
				(type default)
			)
			(layer "B.SilkS")
		)
		(fp_line
			(start 0.67945 -0.305054)
			(end 0.12065 -0.305054)
			(stroke
				(width 0.1)
				(type default)
			)
			(layer "B.Fab")
		)
		(fp_line
			(start 0.12065 -0.305054)
			(end 0.12065 -0.2794)
			(stroke
				(width 0.1)
				(type default)
			)
			(layer "B.Fab")
		)
		(fp_line
			(start -0.12065 -0.3048)
			(end -0.67945 -0.3048)
			(stroke
				(width 0.1)
				(type default)
			)
			(layer "B.Fab")
		)
		(fp_line
			(start -0.67945 -0.3048)
			(end -0.67945 0.3048)
			(stroke
				(width 0.1)
				(type default)
			)
			(layer "B.Fab")
		)
		(fp_line
			(start 0.12065 -0.2794)
			(end -0.12065 -0.2794)
			(stroke
				(width 0.1)
				(type default)
			)
			(layer "B.Fab")
		)
		(fp_line
			(start -0.12065 -0.2794)
			(end -0.12065 -0.3048)
			(stroke
				(width 0.1)
				(type default)
			)
			(layer "B.Fab")
		)
		(fp_line
			(start 0.12065 0.2794)
			(end 0.12065 0.3048)
			(stroke
				(width 0.1)
				(type default)
			)
			(layer "B.Fab")
		)
		(fp_line
			(start -0.120396 0.2794)
			(end 0.12065 0.2794)
			(stroke
				(width 0.1)
				(type default)
			)
			(layer "B.Fab")
		)
		(fp_line
			(start 0.67945 0.3048)
			(end 0.67945 -0.305054)
			(stroke
				(width 0.1)
				(type default)
			)
			(layer "B.Fab")
		)
		(fp_line
			(start 0.12065 0.3048)
			(end 0.67945 0.3048)
			(stroke
				(width 0.1)
				(type default)
			)
			(layer "B.Fab")
		)
		(fp_line
			(start -0.120396 0.3048)
			(end -0.120396 0.2794)
			(stroke
				(width 0.1)
				(type default)
			)
			(layer "B.Fab")
		)
		(fp_line
			(start -0.67945 0.3048)
			(end -0.120396 0.3048)
			(stroke
				(width 0.1)
				(type default)
			)
			(layer "B.Fab")
		)
		(pad "1" smd circle
			(at 0.40005 0 270)
			(size 0 0)
			(layers "B.Cu" "B.Mask" "B.Paste")
			(net "VFG3P3_CLK_GEN")
		)
		(pad "2" smd circle
			(at -0.40005 0 270)
			(size 0 0)
			(layers "B.Cu" "B.Mask" "B.Paste")
			(net "GND")
		)
	)
)
